(kicad_pcb
	(version 20260206)
	(generator "pcbnew")
	(generator_version "10.0")
	(general
		(thickness 1.6)
		(legacy_teardrops no)
	)
	(paper "A4")
	(title_block
		(title "12092022_DA0F0TMDCD0_F0T_Management_Board_D_brd_V3_OCP.brd")
		(comment 1 "Grand Teton / footprints 324-329 of 1440")
	)
	(layers
		(0 "F.Cu" signal "TOP")
		(4 "In1.Cu" signal "GND")
		(6 "In2.Cu" signal "IN1")
		(8 "In3.Cu" signal "GND1")
		(10 "In4.Cu" signal "IN2")
		(12 "In5.Cu" signal "VCC")
		(14 "In6.Cu" signal "VCC1")
		(16 "In7.Cu" signal "IN3")
		(18 "In8.Cu" signal "GND2")
		(20 "In9.Cu" signal "IN4")
		(22 "In10.Cu" signal "GND3")
		(2 "B.Cu" signal "BOTTOM")
		(9 "F.Adhes" user "F.Adhesive")
		(11 "B.Adhes" user "B.Adhesive")
		(13 "F.Paste" user "Package Geometry/Pastemask Top")
		(15 "B.Paste" user "Package Geometry/Pastemask Bottom")
		(5 "F.SilkS" user "Ref Des/Silkscreen Top")
		(7 "B.SilkS" user "Ref Des/Silkscreen Bottom")
		(1 "F.Mask" user "Board Geometry/Soldermask Top")
		(3 "B.Mask" user "Board Geometry/Soldermask Bottom")
		(17 "Dwgs.User" user "User.Drawings")
		(19 "Cmts.User" user "User.Comments")
		(21 "Eco1.User" user "User.Eco1")
		(23 "Eco2.User" user "User.Eco2")
		(25 "Edge.Cuts" user "Board Geometry/Outline")
		(27 "Margin" user)
		(31 "F.CrtYd" user "Package Geometry/Place Bound Top")
		(29 "B.CrtYd" user "Package Geometry/Place Bound Bottom")
		(35 "F.Fab" user "Ref Des/Assembly Top")
		(33 "B.Fab" user "Ref Des/Assembly Bottom")
	)
	(footprint ""
		(layer "F.Cu")
		(at 49.2125 -96.012 90)
		(property "Reference" "R289"
			(at 0 0 90)
			(layer "F.SilkS")
			(hide yes)
			(effects
				(font
					(size 1.27 1.27)
				)
			)
		)
		(property "Value" ""
			(at 0 0 90)
			(layer "F.Fab")
			(effects
				(font
					(size 1.27 1.27)
				)
			)
		)
		(duplicate_pad_numbers_are_jumpers no)
		(fp_line
			(start 0.7874 -0.4064)
			(end 0.7874 0.4064)
			(stroke
				(width 0.1524)
				(type default)
			)
			(layer "F.SilkS")
		)
		(fp_line
			(start -0.7874 -0.4064)
			(end 0.7874 -0.4064)
			(stroke
				(width 0.1524)
				(type default)
			)
			(layer "F.SilkS")
		)
		(fp_line
			(start 0.7874 0.4064)
			(end -0.7874 0.4064)
			(stroke
				(width 0.1524)
				(type default)
			)
			(layer "F.SilkS")
		)
		(fp_line
			(start -0.7874 0.4064)
			(end -0.7874 -0.4064)
			(stroke
				(width 0.1524)
				(type default)
			)
			(layer "F.SilkS")
		)
		(fp_line
			(start -0.12065 -0.305054)
			(end -0.12065 -0.2794)
			(stroke
				(width 0.1)
				(type default)
			)
			(layer "F.Fab")
		)
		(fp_line
			(start -0.67945 -0.305054)
			(end -0.12065 -0.305054)
			(stroke
				(width 0.1)
				(type default)
			)
			(layer "F.Fab")
		)
		(fp_line
			(start 0.67945 -0.3048)
			(end 0.67945 0.3048)
			(stroke
				(width 0.1)
				(type default)
			)
			(layer "F.Fab")
		)
		(fp_line
			(start 0.12065 -0.3048)
			(end 0.67945 -0.3048)
			(stroke
				(width 0.1)
				(type default)
			)
			(layer "F.Fab")
		)
		(fp_line
			(start 0.12065 -0.2794)
			(end 0.12065 -0.3048)
			(stroke
				(width 0.1)
				(type default)
			)
			(layer "F.Fab")
		)
		(fp_line
			(start -0.12065 -0.2794)
			(end 0.12065 -0.2794)
			(stroke
				(width 0.1)
				(type default)
			)
			(layer "F.Fab")
		)
		(fp_line
			(start 0.120396 0.2794)
			(end -0.12065 0.2794)
			(stroke
				(width 0.1)
				(type default)
			)
			(layer "F.Fab")
		)
		(fp_line
			(start -0.12065 0.2794)
			(end -0.12065 0.3048)
			(stroke
				(width 0.1)
				(type default)
			)
			(layer "F.Fab")
		)
		(fp_line
			(start 0.67945 0.3048)
			(end 0.120396 0.3048)
			(stroke
				(width 0.1)
				(type default)
			)
			(layer "F.Fab")
		)
		(fp_line
			(start 0.120396 0.3048)
			(end 0.120396 0.2794)
			(stroke
				(width 0.1)
				(type default)
			)
			(layer "F.Fab")
		)
		(fp_line
			(start -0.12065 0.3048)
			(end -0.67945 0.3048)
			(stroke
				(width 0.1)
				(type default)
			)
			(layer "F.Fab")
		)
		(fp_line
			(start -0.67945 0.3048)
			(end -0.67945 -0.305054)
			(stroke
				(width 0.1)
				(type default)
			)
			(layer "F.Fab")
		)
		(pad "1" smd circle
			(at -0.40005 0 90)
			(size 0 0)
			(layers "F.Cu" "F.Mask" "F.Paste")
			(net "P3V3_RGM")
		)
		(pad "2" smd circle
			(at 0.40005 0 90)
			(size 0 0)
			(layers "F.Cu" "F.Mask" "F.Paste")
			(net "BJT_Q3_C")
		)
	)
	(footprint ""
		(layer "F.Cu")
		(at 42.828464 -30.867604 90)
		(property "Reference" "R706"
			(at 0 0 90)
			(layer "F.SilkS")
			(hide yes)
			(effects
				(font
					(size 1.27 1.27)
				)
			)
		)
		(property "Value" ""
			(at 0 0 90)
			(layer "F.Fab")
			(effects
				(font
					(size 1.27 1.27)
				)
			)
		)
		(duplicate_pad_numbers_are_jumpers no)
		(fp_line
			(start 0.7874 -0.4064)
			(end 0.7874 0.4064)
			(stroke
				(width 0.1524)
				(type default)
			)
			(layer "F.SilkS")
		)
		(fp_line
			(start -0.7874 -0.4064)
			(end 0.7874 -0.4064)
			(stroke
				(width 0.1524)
				(type default)
			)
			(layer "F.SilkS")
		)
		(fp_line
			(start 0.7874 0.4064)
			(end -0.7874 0.4064)
			(stroke
				(width 0.1524)
				(type default)
			)
			(layer "F.SilkS")
		)
		(fp_line
			(start -0.7874 0.4064)
			(end -0.7874 -0.4064)
			(stroke
				(width 0.1524)
				(type default)
			)
			(layer "F.SilkS")
		)
		(fp_line
			(start -0.12065 -0.305054)
			(end -0.12065 -0.2794)
			(stroke
				(width 0.1)
				(type default)
			)
			(layer "F.Fab")
		)
		(fp_line
			(start -0.67945 -0.305054)
			(end -0.12065 -0.305054)
			(stroke
				(width 0.1)
				(type default)
			)
			(layer "F.Fab")
		)
		(fp_line
			(start 0.67945 -0.3048)
			(end 0.67945 0.3048)
			(stroke
				(width 0.1)
				(type default)
			)
			(layer "F.Fab")
		)
		(fp_line
			(start 0.12065 -0.3048)
			(end 0.67945 -0.3048)
			(stroke
				(width 0.1)
				(type default)
			)
			(layer "F.Fab")
		)
		(fp_line
			(start 0.12065 -0.2794)
			(end 0.12065 -0.3048)
			(stroke
				(width 0.1)
				(type default)
			)
			(layer "F.Fab")
		)
		(fp_line
			(start -0.12065 -0.2794)
			(end 0.12065 -0.2794)
			(stroke
				(width 0.1)
				(type default)
			)
			(layer "F.Fab")
		)
		(fp_line
			(start 0.120396 0.2794)
			(end -0.12065 0.2794)
			(stroke
				(width 0.1)
				(type default)
			)
			(layer "F.Fab")
		)
		(fp_line
			(start -0.12065 0.2794)
			(end -0.12065 0.3048)
			(stroke
				(width 0.1)
				(type default)
			)
			(layer "F.Fab")
		)
		(fp_line
			(start 0.67945 0.3048)
			(end 0.120396 0.3048)
			(stroke
				(width 0.1)
				(type default)
			)
			(layer "F.Fab")
		)
		(fp_line
			(start 0.120396 0.3048)
			(end 0.120396 0.2794)
			(stroke
				(width 0.1)
				(type default)
			)
			(layer "F.Fab")
		)
		(fp_line
			(start -0.12065 0.3048)
			(end -0.67945 0.3048)
			(stroke
				(width 0.1)
				(type default)
			)
			(layer "F.Fab")
		)
		(fp_line
			(start -0.67945 0.3048)
			(end -0.67945 -0.305054)
			(stroke
				(width 0.1)
				(type default)
			)
			(layer "F.Fab")
		)
		(pad "1" smd circle
			(at -0.40005 0 90)
			(size 0 0)
			(layers "F.Cu" "F.Mask" "F.Paste")
			(net "P3V3_AUX")
		)
		(pad "2" smd circle
			(at 0.40005 0 90)
			(size 0 0)
			(layers "F.Cu" "F.Mask" "F.Paste")
			(net "FM_BMC_DBP_PRESENT_N")
		)
	)
	(footprint ""
		(layer "F.Cu")
		(at 58.039 -84.709 90)
		(property "Reference" "R753"
			(at 0 0 90)
			(layer "F.SilkS")
			(hide yes)
			(effects
				(font
					(size 1.27 1.27)
				)
			)
		)
		(property "Value" ""
			(at 0 0 90)
			(layer "F.Fab")
			(effects
				(font
					(size 1.27 1.27)
				)
			)
		)
		(duplicate_pad_numbers_are_jumpers no)
		(fp_line
			(start 0.7874 -0.4064)
			(end 0.7874 0.4064)
			(stroke
				(width 0.1524)
				(type default)
			)
			(layer "F.SilkS")
		)
		(fp_line
			(start -0.7874 -0.4064)
			(end 0.7874 -0.4064)
			(stroke
				(width 0.1524)
				(type default)
			)
			(layer "F.SilkS")
		)
		(fp_line
			(start 0.7874 0.4064)
			(end -0.7874 0.4064)
			(stroke
				(width 0.1524)
				(type default)
			)
			(layer "F.SilkS")
		)
		(fp_line
			(start -0.7874 0.4064)
			(end -0.7874 -0.4064)
			(stroke
				(width 0.1524)
				(type default)
			)
			(layer "F.SilkS")
		)
		(fp_line
			(start -0.12065 -0.305054)
			(end -0.12065 -0.2794)
			(stroke
				(width 0.1)
				(type default)
			)
			(layer "F.Fab")
		)
		(fp_line
			(start -0.67945 -0.305054)
			(end -0.12065 -0.305054)
			(stroke
				(width 0.1)
				(type default)
			)
			(layer "F.Fab")
		)
		(fp_line
			(start 0.67945 -0.3048)
			(end 0.67945 0.3048)
			(stroke
				(width 0.1)
				(type default)
			)
			(layer "F.Fab")
		)
		(fp_line
			(start 0.12065 -0.3048)
			(end 0.67945 -0.3048)
			(stroke
				(width 0.1)
				(type default)
			)
			(layer "F.Fab")
		)
		(fp_line
			(start 0.12065 -0.2794)
			(end 0.12065 -0.3048)
			(stroke
				(width 0.1)
				(type default)
			)
			(layer "F.Fab")
		)
		(fp_line
			(start -0.12065 -0.2794)
			(end 0.12065 -0.2794)
			(stroke
				(width 0.1)
				(type default)
			)
			(layer "F.Fab")
		)
		(fp_line
			(start 0.120396 0.2794)
			(end -0.12065 0.2794)
			(stroke
				(width 0.1)
				(type default)
			)
			(layer "F.Fab")
		)
		(fp_line
			(start -0.12065 0.2794)
			(end -0.12065 0.3048)
			(stroke
				(width 0.1)
				(type default)
			)
			(layer "F.Fab")
		)
		(fp_line
			(start 0.67945 0.3048)
			(end 0.120396 0.3048)
			(stroke
				(width 0.1)
				(type default)
			)
			(layer "F.Fab")
		)
		(fp_line
			(start 0.120396 0.3048)
			(end 0.120396 0.2794)
			(stroke
				(width 0.1)
				(type default)
			)
			(layer "F.Fab")
		)
		(fp_line
			(start -0.12065 0.3048)
			(end -0.67945 0.3048)
			(stroke
				(width 0.1)
				(type default)
			)
			(layer "F.Fab")
		)
		(fp_line
			(start -0.67945 0.3048)
			(end -0.67945 -0.305054)
			(stroke
				(width 0.1)
				(type default)
			)
			(layer "F.Fab")
		)
		(pad "1" smd circle
			(at -0.40005 0 90)
			(size 0 0)
			(layers "F.Cu" "F.Mask" "F.Paste")
			(net "P3V3_AUX")
		)
		(pad "2" smd circle
			(at 0.40005 0 90)
			(size 0 0)
			(layers "F.Cu" "F.Mask" "F.Paste")
			(net "SPI_BMC_BOOT_MISO")
		)
	)
	(footprint ""
		(layer "F.Cu")
		(at 55.7784 -109.3978 -90)
		(property "Reference" "R864"
			(at 0 0 270)
			(layer "F.SilkS")
			(hide yes)
			(effects
				(font
					(size 1.27 1.27)
				)
			)
		)
		(property "Value" ""
			(at 0 0 270)
			(layer "F.Fab")
			(effects
				(font
					(size 1.27 1.27)
				)
			)
		)
		(duplicate_pad_numbers_are_jumpers no)
		(fp_line
			(start -0.7874 0.4064)
			(end -0.7874 -0.4064)
			(stroke
				(width 0.1524)
				(type default)
			)
			(layer "F.SilkS")
		)
		(fp_line
			(start 0.7874 0.4064)
			(end -0.7874 0.4064)
			(stroke
				(width 0.1524)
				(type default)
			)
			(layer "F.SilkS")
		)
		(fp_line
			(start -0.7874 -0.4064)
			(end 0.7874 -0.4064)
			(stroke
				(width 0.1524)
				(type default)
			)
			(layer "F.SilkS")
		)
		(fp_line
			(start 0.7874 -0.4064)
			(end 0.7874 0.4064)
			(stroke
				(width 0.1524)
				(type default)
			)
			(layer "F.SilkS")
		)
		(fp_line
			(start -0.67945 0.3048)
			(end -0.67945 -0.305054)
			(stroke
				(width 0.1)
				(type default)
			)
			(layer "F.Fab")
		)
		(fp_line
			(start -0.12065 0.3048)
			(end -0.67945 0.3048)
			(stroke
				(width 0.1)
				(type default)
			)
			(layer "F.Fab")
		)
		(fp_line
			(start 0.120396 0.3048)
			(end 0.120396 0.2794)
			(stroke
				(width 0.1)
				(type default)
			)
			(layer "F.Fab")
		)
		(fp_line
			(start 0.67945 0.3048)
			(end 0.120396 0.3048)
			(stroke
				(width 0.1)
				(type default)
			)
			(layer "F.Fab")
		)
		(fp_line
			(start -0.12065 0.2794)
			(end -0.12065 0.3048)
			(stroke
				(width 0.1)
				(type default)
			)
			(layer "F.Fab")
		)
		(fp_line
			(start 0.120396 0.2794)
			(end -0.12065 0.2794)
			(stroke
				(width 0.1)
				(type default)
			)
			(layer "F.Fab")
		)
		(fp_line
			(start -0.12065 -0.2794)
			(end 0.12065 -0.2794)
			(stroke
				(width 0.1)
				(type default)
			)
			(layer "F.Fab")
		)
		(fp_line
			(start 0.12065 -0.2794)
			(end 0.12065 -0.3048)
			(stroke
				(width 0.1)
				(type default)
			)
			(layer "F.Fab")
		)
		(fp_line
			(start 0.12065 -0.3048)
			(end 0.67945 -0.3048)
			(stroke
				(width 0.1)
				(type default)
			)
			(layer "F.Fab")
		)
		(fp_line
			(start 0.67945 -0.3048)
			(end 0.67945 0.3048)
			(stroke
				(width 0.1)
				(type default)
			)
			(layer "F.Fab")
		)
		(fp_line
			(start -0.67945 -0.305054)
			(end -0.12065 -0.305054)
			(stroke
				(width 0.1)
				(type default)
			)
			(layer "F.Fab")
		)
		(fp_line
			(start -0.12065 -0.305054)
			(end -0.12065 -0.2794)
			(stroke
				(width 0.1)
				(type default)
			)
			(layer "F.Fab")
		)
		(pad "1" smd circle
			(at -0.40005 0 270)
			(size 0 0)
			(layers "F.Cu" "F.Mask" "F.Paste")
			(net "SPI_SYS_CS0_N")
		)
		(pad "2" smd circle
			(at 0.40005 0 270)
			(size 0 0)
			(layers "F.Cu" "F.Mask" "F.Paste")
			(net "SPI_PCH_SECURE_CS0_N")
		)
	)
	(footprint ""
		(layer "F.Cu")
		(at 72.1614 -106.2482 90)
		(property "Reference" "R822"
			(at 0 0 90)
			(layer "F.SilkS")
			(hide yes)
			(effects
				(font
					(size 1.27 1.27)
				)
			)
		)
		(property "Value" ""
			(at 0 0 90)
			(layer "F.Fab")
			(effects
				(font
					(size 1.27 1.27)
				)
			)
		)
		(duplicate_pad_numbers_are_jumpers no)
		(fp_line
			(start 0.7874 -0.4064)
			(end 0.7874 0.4064)
			(stroke
				(width 0.1524)
				(type default)
			)
			(layer "F.SilkS")
		)
		(fp_line
			(start -0.7874 -0.4064)
			(end 0.7874 -0.4064)
			(stroke
				(width 0.1524)
				(type default)
			)
			(layer "F.SilkS")
		)
		(fp_line
			(start 0.7874 0.4064)
			(end -0.7874 0.4064)
			(stroke
				(width 0.1524)
				(type default)
			)
			(layer "F.SilkS")
		)
		(fp_line
			(start -0.7874 0.4064)
			(end -0.7874 -0.4064)
			(stroke
				(width 0.1524)
				(type default)
			)
			(layer "F.SilkS")
		)
		(fp_line
			(start -0.12065 -0.305054)
			(end -0.12065 -0.2794)
			(stroke
				(width 0.1)
				(type default)
			)
			(layer "F.Fab")
		)
		(fp_line
			(start -0.67945 -0.305054)
			(end -0.12065 -0.305054)
			(stroke
				(width 0.1)
				(type default)
			)
			(layer "F.Fab")
		)
		(fp_line
			(start 0.67945 -0.3048)
			(end 0.67945 0.3048)
			(stroke
				(width 0.1)
				(type default)
			)
			(layer "F.Fab")
		)
		(fp_line
			(start 0.12065 -0.3048)
			(end 0.67945 -0.3048)
			(stroke
				(width 0.1)
				(type default)
			)
			(layer "F.Fab")
		)
		(fp_line
			(start 0.12065 -0.2794)
			(end 0.12065 -0.3048)
			(stroke
				(width 0.1)
				(type default)
			)
			(layer "F.Fab")
		)
		(fp_line
			(start -0.12065 -0.2794)
			(end 0.12065 -0.2794)
			(stroke
				(width 0.1)
				(type default)
			)
			(layer "F.Fab")
		)
		(fp_line
			(start 0.120396 0.2794)
			(end -0.12065 0.2794)
			(stroke
				(width 0.1)
				(type default)
			)
			(layer "F.Fab")
		)
		(fp_line
			(start -0.12065 0.2794)
			(end -0.12065 0.3048)
			(stroke
				(width 0.1)
				(type default)
			)
			(layer "F.Fab")
		)
		(fp_line
			(start 0.67945 0.3048)
			(end 0.120396 0.3048)
			(stroke
				(width 0.1)
				(type default)
			)
			(layer "F.Fab")
		)
		(fp_line
			(start 0.120396 0.3048)
			(end 0.120396 0.2794)
			(stroke
				(width 0.1)
				(type default)
			)
			(layer "F.Fab")
		)
		(fp_line
			(start -0.12065 0.3048)
			(end -0.67945 0.3048)
			(stroke
				(width 0.1)
				(type default)
			)
			(layer "F.Fab")
		)
		(fp_line
			(start -0.67945 0.3048)
			(end -0.67945 -0.305054)
			(stroke
				(width 0.1)
				(type default)
			)
			(layer "F.Fab")
		)
		(pad "1" smd circle
			(at -0.40005 0 90)
			(size 0 0)
			(layers "F.Cu" "F.Mask" "F.Paste")
			(net "FM_PRSNT_1_N")
		)
		(pad "2" smd circle
			(at 0.40005 0 90)
			(size 0 0)
			(layers "F.Cu" "F.Mask" "F.Paste")
			(net "FM_PRSNT_0_R_N")
		)
	)
	(footprint ""
		(layer "F.Cu")
		(at 84.201 -96.774)
		(property "Reference" "R414"
			(at 0 0 0)
			(layer "F.SilkS")
			(hide yes)
			(effects
				(font
					(size 1.27 1.27)
				)
			)
		)
		(property "Value" ""
			(at 0 0 0)
			(layer "F.Fab")
			(effects
				(font
					(size 1.27 1.27)
				)
			)
		)
		(duplicate_pad_numbers_are_jumpers no)
		(fp_line
			(start -0.7874 -0.4064)
			(end 0.7874 -0.4064)
			(stroke
				(width 0.1524)
				(type default)
			)
			(layer "F.SilkS")
		)
		(fp_line
			(start -0.7874 0.4064)
			(end -0.7874 -0.4064)
			(stroke
				(width 0.1524)
				(type default)
			)
			(layer "F.SilkS")
		)
		(fp_line
			(start 0.7874 -0.4064)
			(end 0.7874 0.4064)
			(stroke
				(width 0.1524)
				(type default)
			)
			(layer "F.SilkS")
		)
		(fp_line
			(start 0.7874 0.4064)
			(end -0.7874 0.4064)
			(stroke
				(width 0.1524)
				(type default)
			)
			(layer "F.SilkS")
		)
		(fp_line
			(start -0.67945 -0.305054)
			(end -0.12065 -0.305054)
			(stroke
				(width 0.1)
				(type default)
			)
			(layer "F.Fab")
		)
		(fp_line
			(start -0.67945 0.3048)
			(end -0.67945 -0.305054)
			(stroke
				(width 0.1)
				(type default)
			)
			(layer "F.Fab")
		)
		(fp_line
			(start -0.12065 -0.305054)
			(end -0.12065 -0.2794)
			(stroke
				(width 0.1)
				(type default)
			)
			(layer "F.Fab")
		)
		(fp_line
			(start -0.12065 -0.2794)
			(end 0.12065 -0.2794)
			(stroke
				(width 0.1)
				(type default)
			)
			(layer "F.Fab")
		)
		(fp_line
			(start -0.12065 0.2794)
			(end -0.12065 0.3048)
			(stroke
				(width 0.1)
				(type default)
			)
			(layer "F.Fab")
		)
		(fp_line
			(start -0.12065 0.3048)
			(end -0.67945 0.3048)
			(stroke
				(width 0.1)
				(type default)
			)
			(layer "F.Fab")
		)
		(fp_line
			(start 0.120396 0.2794)
			(end -0.12065 0.2794)
			(stroke
				(width 0.1)
				(type default)
			)
			(layer "F.Fab")
		)
		(fp_line
			(start 0.120396 0.3048)
			(end 0.120396 0.2794)
			(stroke
				(width 0.1)
				(type default)
			)
			(layer "F.Fab")
		)
		(fp_line
			(start 0.12065 -0.3048)
			(end 0.67945 -0.3048)
			(stroke
				(width 0.1)
				(type default)
			)
			(layer "F.Fab")
		)
		(fp_line
			(start 0.12065 -0.2794)
			(end 0.12065 -0.3048)
			(stroke
				(width 0.1)
				(type default)
			)
			(layer "F.Fab")
		)
		(fp_line
			(start 0.67945 -0.3048)
			(end 0.67945 0.3048)
			(stroke
				(width 0.1)
				(type default)
			)
			(layer "F.Fab")
		)
		(fp_line
			(start 0.67945 0.3048)
			(end 0.120396 0.3048)
			(stroke
				(width 0.1)
				(type default)
			)
			(layer "F.Fab")
		)
		(pad "1" smd circle
			(at -0.40005 0)
			(size 0 0)
			(layers "F.Cu" "F.Mask" "F.Paste")
			(net "P3V3_AUX")
		)
		(pad "2" smd circle
			(at 0.40005 0)
			(size 0 0)
			(layers "F.Cu" "F.Mask" "F.Paste")
			(net "SPI_BMC_TPM_MISO")
		)
	)
)
